#ISCELL
  mstr_misc dns *
  *
#ISCELL
  mstr_symbols design_note *
  *
#ISCELL
  mstr_symbols intel_corp_bpage *
  *
#ISCELL
  mstr_symbols pvccio_cpu1 *
  page206_i1
#ISCELL
  mstr_standard offpage *
  page206_i10
#ISCELL
  mstr_standard offpage *
  page206_i101
#ISCELL
  mstr_standard offpage *
  page206_i102
#ISCELL
  mstr_symbols p3v3_stby *
  page206_i103
#ISCELL
  mstr_symbols p3v3_stby *
  page206_i104
#ISCELL
  mstr_standard offpage *
  page206_i109
#ISCELL
  mstr_standard offpage *
  page206_i11
#CELL
  mstr_discrete res *
  page206_i111
#CELL
  mstr_discrete res *
  page206_i112
#CELL
  mstr_discrete res *
  page206_i113
#CELL
  mstr_discrete cap *
  page206_i114
#ISCELL
  mstr_symbols gnd *
  page206_i115
#CELL
  mstr_discrete res *
  page206_i116
#CELL
  mstr_discrete res *
  page206_i117
#CELL
  mstr_discrete res *
  page206_i119
#ISCELL
  mstr_standard offpage *
  page206_i12
#CELL
  mstr_discrete res *
  page206_i120
#ISCELL
  mstr_standard offpage *
  page206_i13
#CELL
  mstr_controller pxe1610b *
  page206_i130
#CELL
  w_hdl sc22p50v2jn-4gp *
  page206_i137
#CELL
  w_hdl sc22p50v2jn-4gp *
  page206_i138
#CELL
  w_hdl sc22p50v2jn-4gp *
  page206_i139
#ISCELL
  mstr_standard offpage *
  page206_i14
#CELL
  w_hdl sc22p50v2jn-4gp *
  page206_i140
#CELL
  w_hdl sc22p50v2jn-4gp *
  page206_i141
#CELL
  w_hdl sc22p50v2jn-4gp *
  page206_i142
#CELL
  mstr_discrete res *
  page206_i149
#ISCELL
  mstr_standard offpage *
  page206_i15
#CELL
  mstr_discrete res *
  page206_i150
#CELL
  mstr_discrete res *
  page206_i151
#CELL
  mstr_discrete res *
  page206_i152
#CELL
  mstr_discrete res *
  page206_i153
#CELL
  mstr_discrete res *
  page206_i154
#CELL
  mstr_discrete res *
  page206_i155
#CELL
  dev_discrete cap_a *
  page206_i156
#ISCELL
  mstr_standard offpage *
  page206_i16
#ISCELL
  mstr_standard offpage *
  page206_i17
#ISCELL
  mstr_standard offpage *
  page206_i18
#ISCELL
  mstr_standard offpage *
  page206_i23
#ISCELL
  mstr_standard offpage *
  page206_i24
#ISCELL
  mstr_standard offpage *
  page206_i26
#CELL
  dev_discrete cap_a *
  page206_i29
#ISCELL
  mstr_symbols gnd *
  page206_i30
#CELL
  dev_discrete cap_a *
  page206_i31
#ISCELL
  mstr_symbols gnd *
  page206_i32
#CELL
  mstr_discrete res *
  page206_i33
#CELL
  mstr_discrete res *
  page206_i34
#CELL
  mstr_discrete res *
  page206_i35
#CELL
  mstr_discrete res *
  page206_i36
#CELL
  mstr_discrete res *
  page206_i37
#CELL
  mstr_discrete res *
  page206_i38
#CELL
  mstr_discrete res *
  page206_i4
#ISCELL
  mstr_symbols gnd *
  page206_i40
#CELL
  dev_discrete cap_a *
  page206_i41
#CELL
  dev_discrete cap_a *
  page206_i42
#ISCELL
  mstr_symbols gnd *
  page206_i43
#ISCELL
  mstr_symbols gnd *
  page206_i44
#CELL
  mstr_discrete res *
  page206_i46
#ISCELL
  mstr_symbols pvccio_cpu1 *
  page206_i47
#ISCELL
  mstr_symbols vcc_core *
  page206_i48
#CELL
  mstr_discrete res *
  page206_i49
#ISCELL
  mstr_standard offpage *
  page206_i5
#ISCELL
  mstr_standard offpage *
  page206_i50
#CELL
  mstr_discrete res *
  page206_i53
#CELL
  mstr_discrete res *
  page206_i54
#CELL
  mstr_discrete res *
  page206_i56
#ISCELL
  mstr_symbols gnd *
  page206_i57
#CELL
  mstr_discrete res *
  page206_i6
#ISCELL
  mstr_symbols gnd *
  page206_i65
#ISCELL
  mstr_symbols gnd *
  page206_i67
#CELL
  mstr_discrete cap *
  page206_i68
#CELL
  mstr_discrete cap *
  page206_i69
#ISCELL
  mstr_symbols gnd *
  page206_i70
#CELL
  mstr_discrete cap *
  page206_i71
#ISCELL
  mstr_symbols gnd *
  page206_i72
#ISCELL
  mstr_symbols gnd *
  page206_i74
#CELL
  mstr_discrete res *
  page206_i77
#CELL
  mstr_discrete cap *
  page206_i78
#CELL
  mstr_discrete res *
  page206_i79
#ISCELL
  mstr_standard offpage *
  page206_i8
#ISCELL
  mstr_standard offpage *
  page206_i80
#ISCELL
  mstr_standard offpage *
  page206_i81
#ISCELL
  mstr_standard offpage *
  page206_i82
#ISCELL
  mstr_standard offpage *
  page206_i83
#ISCELL
  mstr_standard offpage *
  page206_i84
#ISCELL
  mstr_standard offpage *
  page206_i85
#ISCELL
  mstr_standard offpage *
  page206_i86
#ISCELL
  mstr_standard offpage *
  page206_i87
#ISCELL
  mstr_standard offpage *
  page206_i88
#ISCELL
  mstr_standard offpage *
  page206_i89
#ISCELL
  mstr_standard offpage *
  page206_i9
#ISCELL
  mstr_standard offpage *
  page206_i90
#ISCELL
  mstr_standard offpage *
  page206_i91
#ISCELL
  mstr_standard offpage *
  page206_i92
#ISCELL
  mstr_standard offpage *
  page206_i94
#ISCELL
  mstr_standard offpage *
  page206_i95
#ISCELL
  mstr_standard offpage *
  page206_i96
#ISCELL
  mstr_standard offpage *
  page206_i97
#ISCELL
  mstr_standard offpage *
  page206_i98
#ISCELL
  mstr_standard offpage *
  page206_i99
